(kicad_pcb
	(version 20260206)
	(generator "pcbnew")
	(generator_version "10.0")
	(general
		(thickness 1.6)
		(legacy_teardrops no)
	)
	(paper "A4")
	(title_block
		(title "timecard-production-celestica-r4006 — R4006-B0001-02_R01.brd")
		(comment 1 "Time Appliance Project (Time Card) / footprints 96-100 of 1113")
	)
	(layers
		(0 "F.Cu" signal "TOP")
		(4 "In1.Cu" signal "L02_GND1")
		(6 "In2.Cu" signal "L03_SIG1")
		(8 "In3.Cu" signal "L04_GND2")
		(10 "In4.Cu" signal "L05_VCC1")
		(12 "In5.Cu" signal "L06_VCC2")
		(14 "In6.Cu" signal "L07_GND3")
		(16 "In7.Cu" signal "L08_SIG2")
		(18 "In8.Cu" signal "L09_GND4")
		(2 "B.Cu" signal "BOTTOM")
		(9 "F.Adhes" user "F.Adhesive")
		(11 "B.Adhes" user "B.Adhesive")
		(13 "F.Paste" user "Package Geometry/Pastemask Top")
		(15 "B.Paste" user "Package Geometry/Pastemask Bottom")
		(5 "F.SilkS" user "Ref Des/Silkscreen Top")
		(7 "B.SilkS" user "Ref Des/Silkscreen Bottom")
		(1 "F.Mask" user "Board Geometry/Soldermask Top")
		(3 "B.Mask" user "Board Geometry/Soldermask Bottom")
		(17 "Dwgs.User" user "User.Drawings")
		(19 "Cmts.User" user "User.Comments")
		(21 "Eco1.User" user "User.Eco1")
		(23 "Eco2.User" user "User.Eco2")
		(25 "Edge.Cuts" user "Board Geometry/Outline")
		(27 "Margin" user)
		(31 "F.CrtYd" user "Package Geometry/Place Bound Top")
		(29 "B.CrtYd" user "Package Geometry/Place Bound Bottom")
		(35 "F.Fab" user "Ref Des/Assembly Top")
		(33 "B.Fab" user "Ref Des/Assembly Bottom")
	)
	(footprint ""
		(layer "F.Cu")
		(at 99.3648 -74.803 90)
		(property "Reference" "U20"
			(at 0 2.65557 90)
			(unlocked yes)
			(layer "F.SilkS")
			(effects
				(font
					(size 0.7874 0.5842)
					(thickness 0.1524)
				)
			)
		)
		(property "Value" ""
			(at 0 0 90)
			(layer "F.Fab")
			(effects
				(font
					(size 1.27 1.27)
				)
			)
		)
		(property "Device Type" "ISL80101IRAJZ_DFN10-G222-10136A"
			(at 0.276606 2.583688 90)
			(unlocked yes)
			(layer "F.Fab")
			(hide yes)
			(effects
				(font
					(size 0.7874 0.5842)
					(thickness 0.1524)
				)
			)
		)
		(property "User Part Number" "PARTNUM*"
			(at 0.276606 3.517646 90)
			(unlocked yes)
			(layer "Cmts.User")
			(hide yes)
			(effects
				(font
					(size 0.7874 0.5842)
					(thickness 0.1524)
				)
			)
		)
		(duplicate_pad_numbers_are_jumpers no)
		(fp_line
			(start 2.290318 -1.779016)
			(end 2.290318 1.779016)
			(stroke
				(width 0.1)
				(type default)
			)
			(layer "F.SilkS")
		)
		(fp_line
			(start -2.290318 -1.779016)
			(end 2.290318 -1.779016)
			(stroke
				(width 0.1)
				(type default)
			)
			(layer "F.SilkS")
		)
		(fp_line
			(start 2.290318 1.779016)
			(end -2.290318 1.779016)
			(stroke
				(width 0.1)
				(type default)
			)
			(layer "F.SilkS")
		)
		(fp_line
			(start -2.290318 1.779016)
			(end -2.290318 -1.779016)
			(stroke
				(width 0.1)
				(type default)
			)
			(layer "F.SilkS")
		)
		(fp_poly
			(pts
				(arc
					(start -2.934462 -0.642112)
					(mid -2.934462 -1.404112)
					(end -2.934462 -0.642112)
				)
			)
			(stroke
				(width 0)
				(type default)
			)
			(fill yes)
			(layer "F.SilkS")
		)
		(fp_rect
			(start -0.7239 0.9017)
			(end 0.7239 0.1016)
			(stroke
				(width 0)
				(type default)
			)
			(fill yes)
			(layer "F.Paste")
		)
		(fp_poly
			(pts
				(xy -0.7239 -0.1016)
				(arc
					(start -0.7239 -0.6477)
					(mid -0.290295 -0.468095)
					(end -0.4699 -0.9017)
				)
				(xy 0.7239 -0.9017) (xy 0.7239 -0.1016)
			)
			(stroke
				(width 0)
				(type default)
			)
			(fill yes)
			(layer "F.Paste")
		)
		(fp_poly
			(pts
				(xy -2.544318 2.033016) (xy 2.544318 2.033016) (xy 2.544318 -2.033016) (xy -2.544318 -2.033016)
			)
			(stroke
				(width 0)
				(type default)
			)
			(fill no)
			(layer "F.CrtYd")
		)
		(fp_line
			(start 1.525016 -1.525016)
			(end 1.525016 1.525016)
			(stroke
				(width 0.1)
				(type default)
			)
			(layer "F.Fab")
		)
		(fp_line
			(start -1.525016 -1.525016)
			(end 1.525016 -1.525016)
			(stroke
				(width 0.1)
				(type default)
			)
			(layer "F.Fab")
		)
		(fp_line
			(start 1.525016 1.525016)
			(end -1.525016 1.525016)
			(stroke
				(width 0.1)
				(type default)
			)
			(layer "F.Fab")
		)
		(fp_line
			(start -1.525016 1.525016)
			(end -1.525016 -1.525016)
			(stroke
				(width 0.1)
				(type default)
			)
			(layer "F.Fab")
		)
		(fp_poly
			(pts
				(arc
					(start -2.934462 -0.642112)
					(mid -2.934462 -1.404112)
					(end -2.934462 -0.642112)
				)
			)
			(stroke
				(width 0)
				(type default)
			)
			(fill yes)
			(layer "F.Fab")
		)
		(fp_text user "5"
			(at -2.825496 1.115822 90)
			(unlocked yes)
			(layer "F.SilkS")
			(effects
				(font
					(size 0.7874 0.5842)
					(thickness 0.1524)
				)
			)
		)
		(fp_text user "6"
			(at 2.24663 2.2352 0)
			(unlocked yes)
			(layer "F.SilkS")
			(effects
				(font
					(size 0.7874 0.5842)
					(thickness 0.1524)
				)
			)
		)
		(fp_text user "10"
			(at 2.38633 -1.3208 0)
			(unlocked yes)
			(layer "F.Fab")
			(effects
				(font
					(size 0.7874 0.5842)
					(thickness 0.1524)
				)
			)
		)
		(fp_text user "6"
			(at 2.38633 0.8382 0)
			(unlocked yes)
			(layer "F.Fab")
			(effects
				(font
					(size 0.7874 0.5842)
					(thickness 0.1524)
				)
			)
		)
		(fp_text user "5"
			(at -1.67767 1.9812 0)
			(unlocked yes)
			(layer "F.Fab")
			(effects
				(font
					(size 0.7874 0.5842)
					(thickness 0.1524)
				)
			)
		)
		(pad "1" smd circle
			(at -1.515618 -1.000252 270)
			(size 0 0)
			(layers "F.Cu" "F.Mask" "F.Paste")
			(net "XP1R2V_FPGA")
		)
		(pad "2" smd rect
			(at -1.515618 -0.500126 90)
			(size 1.0414 0.3048)
			(layers "F.Cu" "F.Mask" "F.Paste")
			(net "XP1R2V_FPGA")
		)
		(pad "3" smd rect
			(at -1.515618 0 90)
			(size 1.0414 0.3048)
			(layers "F.Cu" "F.Mask" "F.Paste")
			(net "XP1R2V_FB")
		)
		(pad "4" smd rect
			(at -1.515618 0.500126 90)
			(size 1.0414 0.3048)
			(layers "F.Cu" "F.Mask" "F.Paste")
			(net "XP1R2V_PG_R")
		)
		(pad "5" smd circle
			(at -1.515618 1.000252 90)
			(size 0 0)
			(layers "F.Cu" "F.Mask" "F.Paste")
			(net "SG")
		)
		(pad "6" smd circle
			(at 1.515618 1.000252 90)
			(size 0 0)
			(layers "F.Cu" "F.Mask" "F.Paste")
			(net "XP1R2V_SS")
		)
		(pad "7" smd rect
			(at 1.515618 0.500126 90)
			(size 1.0414 0.3048)
			(layers "F.Cu" "F.Mask" "F.Paste")
			(net "XP1R2V_EN_R")
		)
		(pad "8" smd rect
			(at 1.515618 0 90)
			(size 1.0414 0.3048)
			(layers "F.Cu" "F.Mask" "F.Paste")
			(net "Net_766")
		)
		(pad "9" smd rect
			(at 1.515618 -0.500126 90)
			(size 1.0414 0.3048)
			(layers "F.Cu" "F.Mask" "F.Paste")
			(net "XP1R2V_VIN")
		)
		(pad "10" smd circle
			(at 1.515618 -1.000252 270)
			(size 0 0)
			(layers "F.Cu" "F.Mask" "F.Paste")
			(net "XP1R2V_VIN")
		)
		(pad "11" smd rect
			(at 0 0 90)
			(size 1.4478 1.8034)
			(layers "F.Cu" "F.Mask" "F.Paste")
			(net "SG")
		)
	)
	(footprint ""
		(layer "F.Cu")
		(at 85.974936 -64.3128 90)
		(property "Reference" "C280"
			(at 13.2842 -9.354566 90)
			(unlocked yes)
			(layer "F.SilkS")
			(effects
				(font
					(size 0.7874 0.5842)
					(thickness 0.1524)
				)
			)
		)
		(property "Value" "VAL*"
			(at 0.0762 2.067306 90)
			(unlocked yes)
			(layer "F.Fab")
			(hide yes)
			(effects
				(font
					(size 0.7874 0.5842)
					(thickness 0.1524)
				)
			)
		)
		(property "Device Type" "CAPACITOR-G105-0C106-BM,10UF,2A"
			(at 0.0508 1.127506 90)
			(unlocked yes)
			(layer "F.Fab")
			(hide yes)
			(effects
				(font
					(size 0.7874 0.5842)
					(thickness 0.1524)
				)
			)
		)
		(property "User Part Number" "PARTNUM*"
			(at 0.1016 4.023106 90)
			(unlocked yes)
			(layer "Cmts.User")
			(hide yes)
			(effects
				(font
					(size 0.7874 0.5842)
					(thickness 0.1524)
				)
			)
		)
		(property "Tolerance" "TOL*"
			(at 0.0762 3.032506 90)
			(unlocked yes)
			(layer "Cmts.User")
			(hide yes)
			(effects
				(font
					(size 0.7874 0.5842)
					(thickness 0.1524)
				)
			)
		)
		(duplicate_pad_numbers_are_jumpers no)
		(fp_line
			(start 1.143 -0.5588)
			(end -1.143 -0.5588)
			(stroke
				(width 0.1)
				(type default)
			)
			(layer "F.SilkS")
		)
		(fp_line
			(start -1.143 -0.5588)
			(end -1.143 0.5588)
			(stroke
				(width 0.1)
				(type default)
			)
			(layer "F.SilkS")
		)
		(fp_line
			(start 1.143 0.5588)
			(end 1.143 -0.5588)
			(stroke
				(width 0.1)
				(type default)
			)
			(layer "F.SilkS")
		)
		(fp_line
			(start -1.143 0.5588)
			(end 1.143 0.5588)
			(stroke
				(width 0.1)
				(type default)
			)
			(layer "F.SilkS")
		)
		(fp_rect
			(start -1.143 -0.5588)
			(end 1.143 0.5588)
			(stroke
				(width 0)
				(type default)
			)
			(fill no)
			(layer "F.CrtYd")
		)
		(fp_line
			(start 0.508 -0.3048)
			(end -0.508 -0.3048)
			(stroke
				(width 0.1)
				(type default)
			)
			(layer "F.Fab")
		)
		(fp_line
			(start -0.508 -0.3048)
			(end -0.508 0.3048)
			(stroke
				(width 0.1)
				(type default)
			)
			(layer "F.Fab")
		)
		(fp_line
			(start 0.508 0.3048)
			(end 0.508 -0.3048)
			(stroke
				(width 0.1)
				(type default)
			)
			(layer "F.Fab")
		)
		(fp_line
			(start -0.508 0.3048)
			(end 0.508 0.3048)
			(stroke
				(width 0.1)
				(type default)
			)
			(layer "F.Fab")
		)
		(pad "1" smd rect
			(at -0.5334 0 90)
			(size 0.7112 0.6096)
			(layers "F.Cu" "F.Mask" "F.Paste")
			(net "VDD_BNO085")
		)
		(pad "2" smd rect
			(at 0.5334 0 90)
			(size 0.7112 0.6096)
			(layers "F.Cu" "F.Mask" "F.Paste")
			(net "SG")
		)
		(zone
			(layer "F.Cu")
			(hatch none 0.5)
			(connect_pads
				(clearance 0)
			)
			(min_thickness 0.25)
			(keepout
				(tracks allowed)
				(vias not_allowed)
				(pads allowed)
				(copperpour not_allowed)
				(footprints allowed)
			)
			(placement
				(enabled no)
				(sheetname "")
			)
			(fill
				(thermal_gap 0.5)
				(thermal_bridge_width 0.5)
				(island_removal_mode 0)
			)
			(polygon
				(pts
					(xy 85.670136 -64.2366) (xy 86.279736 -64.2366) (xy 86.279736 -64.389) (xy 85.670136 -64.389)
				)
			)
		)
	)
	(footprint ""
		(layer "F.Cu")
		(at 44.958 -121.539)
		(property "Reference" "SP43"
			(at 0 0 0)
			(layer "F.SilkS")
			(hide yes)
			(effects
				(font
					(size 1.27 1.27)
				)
			)
		)
		(property "Value" ""
			(at 0 0 0)
			(layer "F.Fab")
			(effects
				(font
					(size 1.27 1.27)
				)
			)
		)
		(duplicate_pad_numbers_are_jumpers no)
	)
	(footprint ""
		(layer "F.Cu")
		(at 156.845 -26.543)
		(property "Reference" "U36"
			(at -0.127 2.57937 0)
			(unlocked yes)
			(layer "F.SilkS")
			(effects
				(font
					(size 0.7874 0.5842)
					(thickness 0.1524)
				)
			)
		)
		(property "Value" ""
			(at 0 0 0)
			(layer "F.Fab")
			(effects
				(font
					(size 1.27 1.27)
				)
			)
		)
		(property "Device Type" "LM75BDP_TSSOP8-G220-10215-01"
			(at -0.03175 2.55651 0)
			(unlocked yes)
			(layer "F.Fab")
			(hide yes)
			(effects
				(font
					(size 0.7874 0.5842)
					(thickness 0.1524)
				)
			)
		)
		(property "User Part Number" "PARTNUM*"
			(at -0.037592 3.488182 0)
			(unlocked yes)
			(layer "Cmts.User")
			(hide yes)
			(effects
				(font
					(size 0.7874 0.5842)
					(thickness 0.1524)
				)
			)
		)
		(duplicate_pad_numbers_are_jumpers no)
		(fp_line
			(start -3.3147 -1.45796)
			(end -3.3147 1.45796)
			(stroke
				(width 0.1)
				(type default)
			)
			(layer "F.SilkS")
		)
		(fp_line
			(start -3.3147 1.45796)
			(end -1.778 1.45796)
			(stroke
				(width 0.1)
				(type default)
			)
			(layer "F.SilkS")
		)
		(fp_line
			(start -1.778 -1.778)
			(end -1.778 -1.45796)
			(stroke
				(width 0.1)
				(type default)
			)
			(layer "F.SilkS")
		)
		(fp_line
			(start -1.778 -1.45796)
			(end -3.3147 -1.45796)
			(stroke
				(width 0.1)
				(type default)
			)
			(layer "F.SilkS")
		)
		(fp_line
			(start -1.778 1.45796)
			(end -1.778 1.778)
			(stroke
				(width 0.1)
				(type default)
			)
			(layer "F.SilkS")
		)
		(fp_line
			(start -1.778 1.778)
			(end 1.778 1.778)
			(stroke
				(width 0.1)
				(type default)
			)
			(layer "F.SilkS")
		)
		(fp_line
			(start 1.778 -1.778)
			(end -1.778 -1.778)
			(stroke
				(width 0.1)
				(type default)
			)
			(layer "F.SilkS")
		)
		(fp_line
			(start 1.778 -1.45796)
			(end 1.778 -1.778)
			(stroke
				(width 0.1)
				(type default)
			)
			(layer "F.SilkS")
		)
		(fp_line
			(start 1.778 1.45796)
			(end 3.3147 1.45796)
			(stroke
				(width 0.1)
				(type default)
			)
			(layer "F.SilkS")
		)
		(fp_line
			(start 1.778 1.778)
			(end 1.778 1.45796)
			(stroke
				(width 0.1)
				(type default)
			)
			(layer "F.SilkS")
		)
		(fp_line
			(start 3.3147 -1.45796)
			(end 1.778 -1.45796)
			(stroke
				(width 0.1)
				(type default)
			)
			(layer "F.SilkS")
		)
		(fp_line
			(start 3.3147 1.45796)
			(end 3.3147 -1.45796)
			(stroke
				(width 0.1)
				(type default)
			)
			(layer "F.SilkS")
		)
		(fp_poly
			(pts
				(arc
					(start -3.175 -2.159)
					(mid -3.937 -2.159)
					(end -3.175 -2.159)
				)
			)
			(stroke
				(width 0)
				(type default)
			)
			(fill yes)
			(layer "F.SilkS")
		)
		(fp_rect
			(start -3.5687 2.032)
			(end 3.5687 -2.032)
			(stroke
				(width 0)
				(type default)
			)
			(fill no)
			(layer "F.CrtYd")
		)
		(fp_line
			(start -1.524 -1.524)
			(end 1.524 -1.524)
			(stroke
				(width 0.1)
				(type default)
			)
			(layer "F.Fab")
		)
		(fp_line
			(start -1.524 1.524)
			(end -1.524 -1.524)
			(stroke
				(width 0.1)
				(type default)
			)
			(layer "F.Fab")
		)
		(fp_line
			(start 1.524 -1.524)
			(end 1.524 1.524)
			(stroke
				(width 0.1)
				(type default)
			)
			(layer "F.Fab")
		)
		(fp_line
			(start 1.524 1.524)
			(end -1.524 1.524)
			(stroke
				(width 0.1)
				(type default)
			)
			(layer "F.Fab")
		)
		(fp_poly
			(pts
				(arc
					(start -0.6096 -0.9398)
					(mid -1.3716 -0.9398)
					(end -0.6096 -0.9398)
				)
			)
			(stroke
				(width 0)
				(type default)
			)
			(fill yes)
			(layer "F.Fab")
		)
		(fp_text user "5"
			(at 3.556 2.70637 0)
			(unlocked yes)
			(layer "F.SilkS")
			(effects
				(font
					(size 0.7874 0.5842)
					(thickness 0.1524)
				)
			)
		)
		(fp_text user "8"
			(at 3.937 -2.11963 0)
			(unlocked yes)
			(layer "F.SilkS")
			(effects
				(font
					(size 0.7874 0.5842)
					(thickness 0.1524)
				)
			)
		)
		(fp_text user "4"
			(at -1.8796 1.24587 0)
			(unlocked yes)
			(layer "F.Fab")
			(effects
				(font
					(size 0.7874 0.5842)
					(thickness 0.1524)
				)
			)
		)
		(fp_text user "8"
			(at 2.16281 -0.94996 0)
			(unlocked yes)
			(layer "F.Fab")
			(effects
				(font
					(size 0.7874 0.5842)
					(thickness 0.1524)
				)
			)
		)
		(fp_text user "5"
			(at 2.16281 1.08204 0)
			(unlocked yes)
			(layer "F.Fab")
			(effects
				(font
					(size 0.7874 0.5842)
					(thickness 0.1524)
				)
			)
		)
		(pad "1" smd rect
			(at -2.2987 -0.97536 90)
			(size 0.4572 1.524)
			(layers "F.Cu" "F.Mask" "F.Paste")
			(net "R_LM75B_3_I2C_SDA")
		)
		(pad "2" smd rect
			(at -2.2987 -0.32512 90)
			(size 0.4572 1.524)
			(layers "F.Cu" "F.Mask" "F.Paste")
			(net "LM75B_I2C_SCL")
		)
		(pad "3" smd rect
			(at -2.2987 0.32512 90)
			(size 0.4572 1.524)
			(layers "F.Cu" "F.Mask" "F.Paste")
			(net "FPGA_IN_LM75B_INT3_N")
		)
		(pad "4" smd rect
			(at -2.2987 0.97536 90)
			(size 0.4572 1.524)
			(layers "F.Cu" "F.Mask" "F.Paste")
			(net "SG")
		)
		(pad "5" smd rect
			(at 2.2987 0.97536 90)
			(size 0.4572 1.524)
			(layers "F.Cu" "F.Mask" "F.Paste")
			(net "UNNAMED_6_LM75BDPTSSOP8_I81_A2")
		)
		(pad "6" smd rect
			(at 2.2987 0.32512 90)
			(size 0.4572 1.524)
			(layers "F.Cu" "F.Mask" "F.Paste")
			(net "UNNAMED_6_LM75BDPTSSOP8_I81_A1")
		)
		(pad "7" smd rect
			(at 2.2987 -0.32512 90)
			(size 0.4572 1.524)
			(layers "F.Cu" "F.Mask" "F.Paste")
			(net "UNNAMED_6_LM75BDPTSSOP8_I81_A0")
		)
		(pad "8" smd rect
			(at 2.2987 -0.97536 90)
			(size 0.4572 1.524)
			(layers "F.Cu" "F.Mask" "F.Paste")
			(net "XP3R3V_FPGA")
		)
	)
	(footprint ""
		(layer "F.Cu")
		(at 15.113 -90.805 90)
		(property "Reference" "R442"
			(at 1.27 -1.10363 90)
			(unlocked yes)
			(layer "F.SilkS")
			(effects
				(font
					(size 0.7874 0.5842)
					(thickness 0.1524)
				)
			)
		)
		(property "Value" "VAL*"
			(at 0.02032 2.13233 90)
			(unlocked yes)
			(layer "F.Fab")
			(hide yes)
			(effects
				(font
					(size 0.7874 0.5842)
					(thickness 0.1524)
				)
			)
		)
		(property "Tolerance" "TOL*"
			(at 0.044704 3.05435 90)
			(unlocked yes)
			(layer "Cmts.User")
			(hide yes)
			(effects
				(font
					(size 0.7874 0.5842)
					(thickness 0.1524)
				)
			)
		)
		(property "User Part Number" "PARTNUM*"
			(at 0.02032 4.024884 90)
			(unlocked yes)
			(layer "Cmts.User")
			(hide yes)
			(effects
				(font
					(size 0.7874 0.5842)
					(thickness 0.1524)
				)
			)
		)
		(property "Device Type" "RESISTOR-G155-05101-01,5.1KOHMA"
			(at 0.008382 1.210564 90)
			(unlocked yes)
			(layer "F.Fab")
			(hide yes)
			(effects
				(font
					(size 0.7874 0.5842)
					(thickness 0.1524)
				)
			)
		)
		(duplicate_pad_numbers_are_jumpers no)
		(fp_line
			(start 1.143 -0.5588)
			(end -1.143 -0.5588)
			(stroke
				(width 0.1)
				(type default)
			)
			(layer "F.SilkS")
		)
		(fp_line
			(start -1.143 -0.5588)
			(end -1.143 0.5588)
			(stroke
				(width 0.1)
				(type default)
			)
			(layer "F.SilkS")
		)
		(fp_line
			(start 1.143 0.5588)
			(end 1.143 -0.5588)
			(stroke
				(width 0.1)
				(type default)
			)
			(layer "F.SilkS")
		)
		(fp_line
			(start -1.143 0.5588)
			(end 1.143 0.5588)
			(stroke
				(width 0.1)
				(type default)
			)
			(layer "F.SilkS")
		)
		(fp_poly
			(pts
				(xy -1.143 0.5588) (xy 1.143 0.5588) (xy 1.143 -0.5588) (xy -1.143 -0.5588)
			)
			(stroke
				(width 0)
				(type default)
			)
			(fill no)
			(layer "F.CrtYd")
		)
		(fp_line
			(start 0.508 -0.3048)
			(end -0.508 -0.3048)
			(stroke
				(width 0.1)
				(type default)
			)
			(layer "F.Fab")
		)
		(fp_line
			(start -0.508 -0.3048)
			(end -0.508 0.3048)
			(stroke
				(width 0.1)
				(type default)
			)
			(layer "F.Fab")
		)
		(fp_line
			(start 0.508 0.3048)
			(end 0.508 -0.3048)
			(stroke
				(width 0.1)
				(type default)
			)
			(layer "F.Fab")
		)
		(fp_line
			(start -0.508 0.3048)
			(end 0.508 0.3048)
			(stroke
				(width 0.1)
				(type default)
			)
			(layer "F.Fab")
		)
		(pad "1" smd rect
			(at -0.5334 0 90)
			(size 0.7112 0.6096)
			(layers "F.Cu" "F.Mask" "F.Paste")
			(net "UNNAMED_524_CONNUSB14PGH4FRATH_")
		)
		(pad "2" smd rect
			(at 0.5334 0 90)
			(size 0.7112 0.6096)
			(layers "F.Cu" "F.Mask" "F.Paste")
			(net "SG")
		)
		(zone
			(layer "F.Cu")
			(hatch none 0.5)
			(connect_pads
				(clearance 0)
			)
			(min_thickness 0.25)
			(keepout
				(tracks allowed)
				(vias not_allowed)
				(pads allowed)
				(copperpour not_allowed)
				(footprints allowed)
			)
			(placement
				(enabled no)
				(sheetname "")
			)
			(fill
				(thermal_gap 0.5)
				(thermal_bridge_width 0.5)
				(island_removal_mode 0)
			)
			(polygon
				(pts
					(xy 15.4178 -90.7288) (xy 15.4178 -90.8812) (xy 14.8082 -90.8812) (xy 14.8082 -90.7288)
				)
			)
		)
		(zone
			(layer "F.Cu")
			(hatch none 0.5)
			(connect_pads
				(clearance 0)
			)
			(min_thickness 0.25)
			(keepout
				(tracks not_allowed)
				(vias allowed)
				(pads allowed)
				(copperpour not_allowed)
				(footprints allowed)
			)
			(placement
				(enabled no)
				(sheetname "")
			)
			(fill
				(thermal_gap 0.5)
				(thermal_bridge_width 0.5)
				(island_removal_mode 0)
			)
			(polygon
				(pts
					(xy 15.4178 -90.7288) (xy 15.4178 -90.8812) (xy 14.8082 -90.8812) (xy 14.8082 -90.7288)
				)
			)
		)
	)
)
